(kicad_pcb
	(version 20260206)
	(generator "pcbnew")
	(generator_version "10.0")
	(general
		(thickness 1.6)
		(legacy_teardrops no)
	)
	(paper "A4")
	(title_block
		(title "timecard-production-celestica-r4006 — R4006-B0001-02_R01.brd")
		(comment 1 "Time Appliance Project (Time Card) / footprints 1085-1089 of 1113")
	)
	(layers
		(0 "F.Cu" signal "TOP")
		(4 "In1.Cu" signal "L02_GND1")
		(6 "In2.Cu" signal "L03_SIG1")
		(8 "In3.Cu" signal "L04_GND2")
		(10 "In4.Cu" signal "L05_VCC1")
		(12 "In5.Cu" signal "L06_VCC2")
		(14 "In6.Cu" signal "L07_GND3")
		(16 "In7.Cu" signal "L08_SIG2")
		(18 "In8.Cu" signal "L09_GND4")
		(2 "B.Cu" signal "BOTTOM")
		(9 "F.Adhes" user "F.Adhesive")
		(11 "B.Adhes" user "B.Adhesive")
		(13 "F.Paste" user "Package Geometry/Pastemask Top")
		(15 "B.Paste" user "Package Geometry/Pastemask Bottom")
		(5 "F.SilkS" user "Ref Des/Silkscreen Top")
		(7 "B.SilkS" user "Ref Des/Silkscreen Bottom")
		(1 "F.Mask" user "Board Geometry/Soldermask Top")
		(3 "B.Mask" user "Board Geometry/Soldermask Bottom")
		(17 "Dwgs.User" user "User.Drawings")
		(19 "Cmts.User" user "User.Comments")
		(21 "Eco1.User" user "User.Eco1")
		(23 "Eco2.User" user "User.Eco2")
		(25 "Edge.Cuts" user "Board Geometry/Outline")
		(27 "Margin" user)
		(31 "F.CrtYd" user "Package Geometry/Place Bound Top")
		(29 "B.CrtYd" user "Package Geometry/Place Bound Bottom")
		(35 "F.Fab" user "Ref Des/Assembly Top")
		(33 "B.Fab" user "Ref Des/Assembly Bottom")
	)
	(footprint ""
		(layer "B.Cu")
		(at 101.092 -87.63 -90)
		(property "Reference" "C123"
			(at 0.127 -1.23063 270)
			(unlocked yes)
			(layer "B.SilkS")
			(effects
				(font
					(size 0.7874 0.5842)
					(thickness 0.1524)
				)
				(justify mirror)
			)
		)
		(property "Value" "VAL*"
			(at -0.0762 2.067306 270)
			(unlocked yes)
			(layer "B.Fab")
			(hide yes)
			(effects
				(font
					(size 0.7874 0.5842)
					(thickness 0.1524)
				)
				(justify mirror)
			)
		)
		(property "Tolerance" "TOL*"
			(at -0.0762 3.032506 270)
			(unlocked yes)
			(layer "Cmts.User")
			(hide yes)
			(effects
				(font
					(size 0.7874 0.5842)
					(thickness 0.1524)
				)
				(justify mirror)
			)
		)
		(property "User Part Number" "PARTNUM*"
			(at -0.1016 4.023106 270)
			(unlocked yes)
			(layer "Cmts.User")
			(hide yes)
			(effects
				(font
					(size 0.7874 0.5842)
					(thickness 0.1524)
				)
				(justify mirror)
			)
		)
		(property "Device Type" "CAPACITOR-G105-0B104-EK,0.1UF,A"
			(at -0.0508 1.127506 270)
			(unlocked yes)
			(layer "B.Fab")
			(hide yes)
			(effects
				(font
					(size 0.7874 0.5842)
					(thickness 0.1524)
				)
				(justify mirror)
			)
		)
		(duplicate_pad_numbers_are_jumpers no)
		(fp_line
			(start -1.143 0.5588)
			(end -1.143 -0.5588)
			(stroke
				(width 0.1)
				(type default)
			)
			(layer "B.SilkS")
		)
		(fp_line
			(start 1.143 0.5588)
			(end -1.143 0.5588)
			(stroke
				(width 0.1)
				(type default)
			)
			(layer "B.SilkS")
		)
		(fp_line
			(start -1.143 -0.5588)
			(end 1.143 -0.5588)
			(stroke
				(width 0.1)
				(type default)
			)
			(layer "B.SilkS")
		)
		(fp_line
			(start 1.143 -0.5588)
			(end 1.143 0.5588)
			(stroke
				(width 0.1)
				(type default)
			)
			(layer "B.SilkS")
		)
		(fp_poly
			(pts
				(xy 1.143 0.5588) (xy -1.143 0.5588) (xy -1.143 -0.5588) (xy 1.143 -0.5588)
			)
			(stroke
				(width 0)
				(type default)
			)
			(fill no)
			(layer "B.CrtYd")
		)
		(fp_line
			(start -0.508 0.3048)
			(end -0.508 -0.3048)
			(stroke
				(width 0.1)
				(type default)
			)
			(layer "B.Fab")
		)
		(fp_line
			(start 0.508 0.3048)
			(end -0.508 0.3048)
			(stroke
				(width 0.1)
				(type default)
			)
			(layer "B.Fab")
		)
		(fp_line
			(start -0.508 -0.3048)
			(end 0.508 -0.3048)
			(stroke
				(width 0.1)
				(type default)
			)
			(layer "B.Fab")
		)
		(fp_line
			(start 0.508 -0.3048)
			(end 0.508 0.3048)
			(stroke
				(width 0.1)
				(type default)
			)
			(layer "B.Fab")
		)
		(pad "1" smd rect
			(at 0.5334 0 90)
			(size 0.7112 0.6096)
			(layers "B.Cu" "B.Mask" "B.Paste")
			(net "XP3R3V_FPGA")
		)
		(pad "2" smd rect
			(at -0.5334 0 90)
			(size 0.7112 0.6096)
			(layers "B.Cu" "B.Mask" "B.Paste")
			(net "SG")
		)
		(zone
			(layer "B.Cu")
			(hatch none 0.5)
			(connect_pads
				(clearance 0)
			)
			(min_thickness 0.25)
			(keepout
				(tracks not_allowed)
				(vias allowed)
				(pads allowed)
				(copperpour not_allowed)
				(footprints allowed)
			)
			(placement
				(enabled no)
				(sheetname "")
			)
			(fill
				(thermal_gap 0.5)
				(thermal_bridge_width 0.5)
				(island_removal_mode 0)
			)
			(polygon
				(pts
					(xy 100.7872 -87.5538) (xy 101.3968 -87.5538) (xy 101.3968 -87.7062) (xy 100.7872 -87.7062)
				)
			)
		)
		(zone
			(layer "B.Cu")
			(hatch none 0.5)
			(connect_pads
				(clearance 0)
			)
			(min_thickness 0.25)
			(keepout
				(tracks allowed)
				(vias not_allowed)
				(pads allowed)
				(copperpour not_allowed)
				(footprints allowed)
			)
			(placement
				(enabled no)
				(sheetname "")
			)
			(fill
				(thermal_gap 0.5)
				(thermal_bridge_width 0.5)
				(island_removal_mode 0)
			)
			(polygon
				(pts
					(xy 100.7872 -87.5538) (xy 101.3968 -87.5538) (xy 101.3968 -87.7062) (xy 100.7872 -87.7062)
				)
			)
		)
	)
	(footprint ""
		(layer "B.Cu")
		(at 77.3938 -82.804 180)
		(property "Reference" "R62"
			(at 2.9718 -0.29337 0)
			(unlocked yes)
			(layer "B.SilkS")
			(effects
				(font
					(size 0.7874 0.5842)
					(thickness 0.1524)
				)
				(justify mirror)
			)
		)
		(property "Value" "VAL*"
			(at -0.02032 2.13233 180)
			(unlocked yes)
			(layer "B.Fab")
			(hide yes)
			(effects
				(font
					(size 0.7874 0.5842)
					(thickness 0.1524)
				)
				(justify mirror)
			)
		)
		(property "Tolerance" "TOL*"
			(at -0.044704 3.05435 180)
			(unlocked yes)
			(layer "Cmts.User")
			(hide yes)
			(effects
				(font
					(size 0.7874 0.5842)
					(thickness 0.1524)
				)
				(justify mirror)
			)
		)
		(property "User Part Number" "PARTNUM*"
			(at -0.02032 4.024884 180)
			(unlocked yes)
			(layer "Cmts.User")
			(hide yes)
			(effects
				(font
					(size 0.7874 0.5842)
					(thickness 0.1524)
				)
				(justify mirror)
			)
		)
		(property "Device Type" "RESISTOR-G155-100R0-J0,0OHM,-"
			(at -0.008382 1.210564 180)
			(unlocked yes)
			(layer "B.Fab")
			(hide yes)
			(effects
				(font
					(size 0.7874 0.5842)
					(thickness 0.1524)
				)
				(justify mirror)
			)
		)
		(duplicate_pad_numbers_are_jumpers no)
		(fp_line
			(start 1.143 0.5588)
			(end -1.143 0.5588)
			(stroke
				(width 0.1)
				(type default)
			)
			(layer "B.SilkS")
		)
		(fp_line
			(start 1.143 -0.5588)
			(end 1.143 0.5588)
			(stroke
				(width 0.1)
				(type default)
			)
			(layer "B.SilkS")
		)
		(fp_line
			(start -1.143 0.5588)
			(end -1.143 -0.5588)
			(stroke
				(width 0.1)
				(type default)
			)
			(layer "B.SilkS")
		)
		(fp_line
			(start -1.143 -0.5588)
			(end 1.143 -0.5588)
			(stroke
				(width 0.1)
				(type default)
			)
			(layer "B.SilkS")
		)
		(fp_poly
			(pts
				(xy 1.143 0.5588) (xy -1.143 0.5588) (xy -1.143 -0.5588) (xy 1.143 -0.5588)
			)
			(stroke
				(width 0)
				(type default)
			)
			(fill no)
			(layer "B.CrtYd")
		)
		(fp_line
			(start 0.508 0.3048)
			(end -0.508 0.3048)
			(stroke
				(width 0.1)
				(type default)
			)
			(layer "B.Fab")
		)
		(fp_line
			(start 0.508 -0.3048)
			(end 0.508 0.3048)
			(stroke
				(width 0.1)
				(type default)
			)
			(layer "B.Fab")
		)
		(fp_line
			(start -0.508 0.3048)
			(end -0.508 -0.3048)
			(stroke
				(width 0.1)
				(type default)
			)
			(layer "B.Fab")
		)
		(fp_line
			(start -0.508 -0.3048)
			(end 0.508 -0.3048)
			(stroke
				(width 0.1)
				(type default)
			)
			(layer "B.Fab")
		)
		(pad "1" smd rect
			(at 0.5334 0)
			(size 0.7112 0.6096)
			(layers "B.Cu" "B.Mask" "B.Paste")
			(net "VDD_PCA9546A")
		)
		(pad "2" smd rect
			(at -0.5334 0)
			(size 0.7112 0.6096)
			(layers "B.Cu" "B.Mask" "B.Paste")
			(net "XP3R3V_FPGA")
		)
		(zone
			(layer "B.Cu")
			(hatch none 0.5)
			(connect_pads
				(clearance 0)
			)
			(min_thickness 0.25)
			(keepout
				(tracks allowed)
				(vias not_allowed)
				(pads allowed)
				(copperpour not_allowed)
				(footprints allowed)
			)
			(placement
				(enabled no)
				(sheetname "")
			)
			(fill
				(thermal_gap 0.5)
				(thermal_bridge_width 0.5)
				(island_removal_mode 0)
			)
			(polygon
				(pts
					(xy 77.3176 -83.1088) (xy 77.3176 -82.4992) (xy 77.47 -82.4992) (xy 77.47 -83.1088)
				)
			)
		)
		(zone
			(layer "B.Cu")
			(hatch none 0.5)
			(connect_pads
				(clearance 0)
			)
			(min_thickness 0.25)
			(keepout
				(tracks not_allowed)
				(vias allowed)
				(pads allowed)
				(copperpour not_allowed)
				(footprints allowed)
			)
			(placement
				(enabled no)
				(sheetname "")
			)
			(fill
				(thermal_gap 0.5)
				(thermal_bridge_width 0.5)
				(island_removal_mode 0)
			)
			(polygon
				(pts
					(xy 77.3176 -83.1088) (xy 77.3176 -82.4992) (xy 77.47 -82.4992) (xy 77.47 -83.1088)
				)
			)
		)
	)
	(footprint ""
		(layer "B.Cu")
		(at 34.925 -90.932 90)
		(property "Reference" "C91"
			(at 3.048 -0.29337 270)
			(unlocked yes)
			(layer "B.SilkS")
			(effects
				(font
					(size 0.7874 0.5842)
					(thickness 0.1524)
				)
				(justify mirror)
			)
		)
		(property "Value" "VAL*"
			(at -0.02032 2.13233 90)
			(unlocked yes)
			(layer "B.Fab")
			(hide yes)
			(effects
				(font
					(size 0.7874 0.5842)
					(thickness 0.1524)
				)
				(justify mirror)
			)
		)
		(property "Tolerance" "TOL*"
			(at -0.044704 3.05435 90)
			(unlocked yes)
			(layer "Cmts.User")
			(hide yes)
			(effects
				(font
					(size 0.7874 0.5842)
					(thickness 0.1524)
				)
				(justify mirror)
			)
		)
		(property "User Part Number" "PARTNUM*"
			(at -0.02032 4.024884 90)
			(unlocked yes)
			(layer "Cmts.User")
			(hide yes)
			(effects
				(font
					(size 0.7874 0.5842)
					(thickness 0.1524)
				)
				(justify mirror)
			)
		)
		(property "Device Type" "CAPACITOR-G105-0F475-BM,4.7UF,A"
			(at -0.008382 1.210564 90)
			(unlocked yes)
			(layer "B.Fab")
			(hide yes)
			(effects
				(font
					(size 0.7874 0.5842)
					(thickness 0.1524)
				)
				(justify mirror)
			)
		)
		(duplicate_pad_numbers_are_jumpers no)
		(fp_line
			(start 1.143 -0.5588)
			(end 1.143 0.5588)
			(stroke
				(width 0.1)
				(type default)
			)
			(layer "B.SilkS")
		)
		(fp_line
			(start -1.143 -0.5588)
			(end 1.143 -0.5588)
			(stroke
				(width 0.1)
				(type default)
			)
			(layer "B.SilkS")
		)
		(fp_line
			(start 1.143 0.5588)
			(end -1.143 0.5588)
			(stroke
				(width 0.1)
				(type default)
			)
			(layer "B.SilkS")
		)
		(fp_line
			(start -1.143 0.5588)
			(end -1.143 -0.5588)
			(stroke
				(width 0.1)
				(type default)
			)
			(layer "B.SilkS")
		)
		(fp_poly
			(pts
				(xy 1.143 0.5588) (xy -1.143 0.5588) (xy -1.143 -0.5588) (xy 1.143 -0.5588)
			)
			(stroke
				(width 0)
				(type default)
			)
			(fill no)
			(layer "B.CrtYd")
		)
		(fp_line
			(start 0.508 -0.3048)
			(end 0.508 0.3048)
			(stroke
				(width 0.1)
				(type default)
			)
			(layer "B.Fab")
		)
		(fp_line
			(start -0.508 -0.3048)
			(end 0.508 -0.3048)
			(stroke
				(width 0.1)
				(type default)
			)
			(layer "B.Fab")
		)
		(fp_line
			(start 0.508 0.3048)
			(end -0.508 0.3048)
			(stroke
				(width 0.1)
				(type default)
			)
			(layer "B.Fab")
		)
		(fp_line
			(start -0.508 0.3048)
			(end -0.508 -0.3048)
			(stroke
				(width 0.1)
				(type default)
			)
			(layer "B.Fab")
		)
		(pad "1" smd rect
			(at 0.5334 0 270)
			(size 0.7112 0.6096)
			(layers "B.Cu" "B.Mask" "B.Paste")
			(net "XP3R3V_FT4232")
		)
		(pad "2" smd rect
			(at -0.5334 0 270)
			(size 0.7112 0.6096)
			(layers "B.Cu" "B.Mask" "B.Paste")
			(net "SG")
		)
		(zone
			(layer "B.Cu")
			(hatch none 0.5)
			(connect_pads
				(clearance 0)
			)
			(min_thickness 0.25)
			(keepout
				(tracks allowed)
				(vias not_allowed)
				(pads allowed)
				(copperpour not_allowed)
				(footprints allowed)
			)
			(placement
				(enabled no)
				(sheetname "")
			)
			(fill
				(thermal_gap 0.5)
				(thermal_bridge_width 0.5)
				(island_removal_mode 0)
			)
			(polygon
				(pts
					(xy 35.2298 -91.0082) (xy 34.6202 -91.0082) (xy 34.6202 -90.8558) (xy 35.2298 -90.8558)
				)
			)
		)
		(zone
			(layer "B.Cu")
			(hatch none 0.5)
			(connect_pads
				(clearance 0)
			)
			(min_thickness 0.25)
			(keepout
				(tracks not_allowed)
				(vias allowed)
				(pads allowed)
				(copperpour not_allowed)
				(footprints allowed)
			)
			(placement
				(enabled no)
				(sheetname "")
			)
			(fill
				(thermal_gap 0.5)
				(thermal_bridge_width 0.5)
				(island_removal_mode 0)
			)
			(polygon
				(pts
					(xy 35.2298 -91.0082) (xy 34.6202 -91.0082) (xy 34.6202 -90.8558) (xy 35.2298 -90.8558)
				)
			)
		)
	)
	(footprint ""
		(layer "B.Cu")
		(at 105.847134 -50.323242 -90)
		(property "Reference" "C119"
			(at 0.412242 -0.928116 270)
			(unlocked yes)
			(layer "B.SilkS")
			(effects
				(font
					(size 0.635 0.4064)
					(thickness 0.1524)
				)
				(justify mirror)
			)
		)
		(property "Value" "VAL*"
			(at 0 3.718306 270)
			(unlocked yes)
			(layer "B.Fab")
			(hide yes)
			(effects
				(font
					(size 0.7874 0.5842)
					(thickness 0.127)
				)
				(justify mirror)
			)
		)
		(property "Device Type" "CAPACITOR-G105-0B104-CK,0.1UF,A"
			(at 0 1.432306 270)
			(unlocked yes)
			(layer "B.Fab")
			(hide yes)
			(effects
				(font
					(size 0.7874 0.5842)
					(thickness 0.127)
				)
				(justify mirror)
			)
		)
		(property "User Part Number" "PARTNUM*"
			(at 0 2.575306 270)
			(unlocked yes)
			(layer "Cmts.User")
			(hide yes)
			(effects
				(font
					(size 0.7874 0.5842)
					(thickness 0.127)
				)
				(justify mirror)
			)
		)
		(property "Tolerance" "TOL*"
			(at 0 4.861306 270)
			(unlocked yes)
			(layer "Cmts.User")
			(hide yes)
			(effects
				(font
					(size 0.7874 0.5842)
					(thickness 0.127)
				)
				(justify mirror)
			)
		)
		(duplicate_pad_numbers_are_jumpers no)
		(fp_line
			(start -0.970026 0.4699)
			(end 0.970026 0.4699)
			(stroke
				(width 0.1)
				(type default)
			)
			(layer "B.SilkS")
		)
		(fp_line
			(start 0.970026 0.4699)
			(end 0.970026 -0.4699)
			(stroke
				(width 0.1)
				(type default)
			)
			(layer "B.SilkS")
		)
		(fp_line
			(start -0.970026 -0.4699)
			(end -0.970026 0.4699)
			(stroke
				(width 0.1)
				(type default)
			)
			(layer "B.SilkS")
		)
		(fp_line
			(start 0.970026 -0.4699)
			(end -0.970026 -0.4699)
			(stroke
				(width 0.1)
				(type default)
			)
			(layer "B.SilkS")
		)
		(fp_poly
			(pts
				(xy 0.970026 0.4699) (xy -0.970026 0.4699) (xy -0.970026 -0.4699) (xy 0.970026 -0.4699)
			)
			(stroke
				(width 0)
				(type default)
			)
			(fill no)
			(layer "B.CrtYd")
		)
		(fp_line
			(start -0.508 0.3048)
			(end 0.508 0.3048)
			(stroke
				(width 0.1)
				(type default)
			)
			(layer "B.Fab")
		)
		(fp_line
			(start 0.508 0.3048)
			(end 0.508 -0.3048)
			(stroke
				(width 0.1)
				(type default)
			)
			(layer "B.Fab")
		)
		(fp_line
			(start -0.508 -0.3048)
			(end -0.508 0.3048)
			(stroke
				(width 0.1)
				(type default)
			)
			(layer "B.Fab")
		)
		(fp_line
			(start 0.508 -0.3048)
			(end -0.508 -0.3048)
			(stroke
				(width 0.1)
				(type default)
			)
			(layer "B.Fab")
		)
		(pad "1" smd circle
			(at 0.500126 0 90)
			(size 0.635 0.635)
			(layers "B.Cu" "B.Mask" "B.Paste")
			(net "XP3R3V_FPGA")
		)
		(pad "2" smd circle
			(at -0.500126 0 90)
			(size 0.635 0.635)
			(layers "B.Cu" "B.Mask" "B.Paste")
			(net "SG")
		)
	)
	(footprint ""
		(layer "B.Cu")
		(at 72.40397 -15.367 -90)
		(property "Reference" "C34"
			(at 2.286 -0.08128 270)
			(unlocked yes)
			(layer "B.SilkS")
			(effects
				(font
					(size 0.635 0.4064)
					(thickness 0.1524)
				)
				(justify mirror)
			)
		)
		(property "Value" "VAL*"
			(at -0.0762 2.067306 270)
			(unlocked yes)
			(layer "B.Fab")
			(hide yes)
			(effects
				(font
					(size 0.7874 0.5842)
					(thickness 0.1524)
				)
				(justify mirror)
			)
		)
		(property "Tolerance" "TOL*"
			(at -0.0762 3.032506 270)
			(unlocked yes)
			(layer "Cmts.User")
			(hide yes)
			(effects
				(font
					(size 0.7874 0.5842)
					(thickness 0.1524)
				)
				(justify mirror)
			)
		)
		(property "User Part Number" "PARTNUM*"
			(at -0.1016 4.023106 270)
			(unlocked yes)
			(layer "Cmts.User")
			(hide yes)
			(effects
				(font
					(size 0.7874 0.5842)
					(thickness 0.1524)
				)
				(justify mirror)
			)
		)
		(property "Device Type" "CAPACITOR-G105-0B104-CK,0.1UF,A"
			(at -0.0508 1.127506 270)
			(unlocked yes)
			(layer "B.Fab")
			(hide yes)
			(effects
				(font
					(size 0.7874 0.5842)
					(thickness 0.1524)
				)
				(justify mirror)
			)
		)
		(duplicate_pad_numbers_are_jumpers no)
		(fp_line
			(start -1.143 0.5588)
			(end -1.143 -0.5588)
			(stroke
				(width 0.1)
				(type default)
			)
			(layer "B.SilkS")
		)
		(fp_line
			(start 1.143 0.5588)
			(end -1.143 0.5588)
			(stroke
				(width 0.1)
				(type default)
			)
			(layer "B.SilkS")
		)
		(fp_line
			(start -1.143 -0.5588)
			(end 1.143 -0.5588)
			(stroke
				(width 0.1)
				(type default)
			)
			(layer "B.SilkS")
		)
		(fp_line
			(start 1.143 -0.5588)
			(end 1.143 0.5588)
			(stroke
				(width 0.1)
				(type default)
			)
			(layer "B.SilkS")
		)
		(fp_rect
			(start 1.143 0.5588)
			(end -1.143 -0.5588)
			(stroke
				(width 0)
				(type default)
			)
			(fill no)
			(layer "B.CrtYd")
		)
		(fp_line
			(start -0.508 0.3048)
			(end -0.508 -0.3048)
			(stroke
				(width 0.1)
				(type default)
			)
			(layer "B.Fab")
		)
		(fp_line
			(start 0.508 0.3048)
			(end -0.508 0.3048)
			(stroke
				(width 0.1)
				(type default)
			)
			(layer "B.Fab")
		)
		(fp_line
			(start -0.508 -0.3048)
			(end 0.508 -0.3048)
			(stroke
				(width 0.1)
				(type default)
			)
			(layer "B.Fab")
		)
		(fp_line
			(start 0.508 -0.3048)
			(end 0.508 0.3048)
			(stroke
				(width 0.1)
				(type default)
			)
			(layer "B.Fab")
		)
		(pad "1" smd rect
			(at 0.5334 0 90)
			(size 0.7112 0.6096)
			(layers "B.Cu" "B.Mask" "B.Paste")
			(net "C_CPU_RX_PCIE_MGT2_TXN")
		)
		(pad "2" smd rect
			(at -0.5334 0 90)
			(size 0.7112 0.6096)
			(layers "B.Cu" "B.Mask" "B.Paste")
			(net "CPU_RX_PCIE_MGT2_TXN")
		)
		(zone
			(layer "B.Cu")
			(hatch none 0.5)
			(connect_pads
				(clearance 0)
			)
			(min_thickness 0.25)
			(keepout
				(tracks allowed)
				(vias not_allowed)
				(pads allowed)
				(copperpour not_allowed)
				(footprints allowed)
			)
			(placement
				(enabled no)
				(sheetname "")
			)
			(fill
				(thermal_gap 0.5)
				(thermal_bridge_width 0.5)
				(island_removal_mode 0)
			)
			(polygon
				(pts
					(xy 72.09917 -15.2908) (xy 72.70877 -15.2908) (xy 72.70877 -15.4432) (xy 72.09917 -15.4432)
				)
			)
		)
	)
)
